(kicad_pcb
	(version 20260206)
	(generator "pcbnew")
	(generator_version "10.0")
	(general
		(thickness 1.6)
		(legacy_teardrops no)
	)
	(paper "A4")
	(title_block
		(title "Wiwynn_Tioga_Pass_MB.brd")
		(comment 1 "Tioga Pass / footprint 1664 of 4770 (U7C1), pads 345-462 of 1310")
	)
	(layers
		(0 "F.Cu" signal "TOP")
		(4 "In1.Cu" signal "L2GND")
		(6 "In2.Cu" signal "L3")
		(8 "In3.Cu" signal "L4GND")
		(10 "In4.Cu" signal "L5")
		(12 "In5.Cu" signal "L6GND")
		(14 "In6.Cu" signal "L7VCC")
		(16 "In7.Cu" signal "L8VCC")
		(18 "In8.Cu" signal "L9GND")
		(20 "In9.Cu" signal "L10")
		(22 "In10.Cu" signal "L11GND")
		(24 "In11.Cu" signal "L12")
		(26 "In12.Cu" signal "L13GND")
		(2 "B.Cu" signal "BOTTOM")
		(9 "F.Adhes" user "F.Adhesive")
		(11 "B.Adhes" user "B.Adhesive")
		(13 "F.Paste" user "Package Geometry/Pastemask Top")
		(15 "B.Paste" user "Package Geometry/Pastemask Bottom")
		(5 "F.SilkS" user "Ref Des/Silkscreen Top")
		(7 "B.SilkS" user "Ref Des/Silkscreen Bottom")
		(1 "F.Mask" user "Board Geometry/Soldermask Top")
		(3 "B.Mask" user "Board Geometry/Soldermask Bottom")
		(17 "Dwgs.User" user "User.Drawings")
		(19 "Cmts.User" user "User.Comments")
		(21 "Eco1.User" user "User.Eco1")
		(23 "Eco2.User" user "User.Eco2")
		(25 "Edge.Cuts" user "Board Geometry/Outline")
		(27 "Margin" user)
		(31 "F.CrtYd" user "Package Geometry/Place Bound Top")
		(29 "B.CrtYd" user "Package Geometry/Place Bound Bottom")
		(35 "F.Fab" user "Ref Des/Assembly Top")
		(33 "B.Fab" user "Ref Des/Assembly Bottom")
	)
	(footprint ""
		(layer "F.Cu")
		(at 387.985 -109.855 90)
		(property "Reference" "U7C1"
			(at 17.75333 -13.335 0)
			(unlocked yes)
			(layer "F.SilkS")
			(effects
				(font
					(size 0.7874 0.5842)
					(thickness 0.1524)
				)
				(justify left)
			)
		)
		(property "Value" ""
			(at 0 0 90)
			(layer "F.Fab")
			(effects
				(font
					(size 1.27 1.27)
				)
			)
		)
		(duplicate_pad_numbers_are_jumpers no)
		(pad "AT2" smd circle
			(at -15.895066 2.500122 180)
			(size 0.3048 0.3048)
			(layers "F.Cu" "F.Mask" "F.Paste")
			(net "Net_462")
		)
		(pad "AT4" smd circle
			(at -15.064994 2.500122 180)
			(size 0.3048 0.3048)
			(layers "F.Cu" "F.Mask" "F.Paste")
			(net "FM_UARTSW_LSB_N")
		)
		(pad "AT7" smd circle
			(at -13.73632 2.22885)
			(size 0.381 0.381)
			(layers "F.Cu" "F.Mask" "F.Paste")
			(net "GND")
		)
		(pad "AT11" smd circle
			(at -12.01928 2.22885)
			(size 0.381 0.381)
			(layers "F.Cu" "F.Mask" "F.Paste")
			(net "GND")
		)
		(pad "AT15" smd circle
			(at -10.30224 2.22885)
			(size 0.381 0.381)
			(layers "F.Cu" "F.Mask" "F.Paste")
			(net "GND")
		)
		(pad "AT18" smd circle
			(at -8.5852 2.22885)
			(size 0.381 0.381)
			(layers "F.Cu" "F.Mask" "F.Paste")
			(net "GND")
		)
		(pad "AT22" smd circle
			(at -6.86816 2.22885)
			(size 0.381 0.381)
			(layers "F.Cu" "F.Mask" "F.Paste")
			(net "GND")
		)
		(pad "AT26" smd circle
			(at -5.20065 2.15265 180)
			(size 0.381 0.381)
			(layers "F.Cu" "F.Mask" "F.Paste")
			(net "GND")
		)
		(pad "AT27" smd circle
			(at -4.40055 2.15265 180)
			(size 0.381 0.381)
			(layers "F.Cu" "F.Mask" "F.Paste")
			(net "TP_PCH_RSVD59")
		)
		(pad "AT29" smd circle
			(at -3.60045 2.15265 180)
			(size 0.381 0.381)
			(layers "F.Cu" "F.Mask" "F.Paste")
			(net "P1V8_PCH_STBY")
		)
		(pad "AT30" smd circle
			(at -2.80035 2.15265 180)
			(size 0.381 0.381)
			(layers "F.Cu" "F.Mask" "F.Paste")
			(net "GND")
		)
		(pad "AT32" smd circle
			(at -2.00025 2.15265 180)
			(size 0.381 0.381)
			(layers "F.Cu" "F.Mask" "F.Paste")
			(net "PVNN_PCH_STBY")
		)
		(pad "AT34" smd circle
			(at -1.20015 2.15265 180)
			(size 0.381 0.381)
			(layers "F.Cu" "F.Mask" "F.Paste")
			(net "PVNN_PCH_STBY")
		)
		(pad "AT36" smd circle
			(at -0.40005 2.15265 180)
			(size 0.381 0.381)
			(layers "F.Cu" "F.Mask" "F.Paste")
			(net "PVNN_PCH_STBY")
		)
		(pad "AT37" smd circle
			(at 0.40005 2.15265 180)
			(size 0.381 0.381)
			(layers "F.Cu" "F.Mask" "F.Paste")
			(net "GND")
		)
		(pad "AT39" smd circle
			(at 1.20015 2.15265 180)
			(size 0.381 0.381)
			(layers "F.Cu" "F.Mask" "F.Paste")
			(net "P1V05_PCH_STBY")
		)
		(pad "AT41" smd circle
			(at 2.00025 2.15265 180)
			(size 0.381 0.381)
			(layers "F.Cu" "F.Mask" "F.Paste")
			(net "GND")
		)
		(pad "AT43" smd circle
			(at 2.80035 2.15265 180)
			(size 0.381 0.381)
			(layers "F.Cu" "F.Mask" "F.Paste")
			(net "P1V05_PCH_STBY")
		)
		(pad "AT45" smd circle
			(at 3.60045 2.15265 180)
			(size 0.381 0.381)
			(layers "F.Cu" "F.Mask" "F.Paste")
			(net "P1V05_PCH_STBY")
		)
		(pad "AT46" smd circle
			(at 4.40055 2.15265 180)
			(size 0.381 0.381)
			(layers "F.Cu" "F.Mask" "F.Paste")
			(net "GND")
		)
		(pad "AT48" smd circle
			(at 5.20065 2.15265 180)
			(size 0.381 0.381)
			(layers "F.Cu" "F.Mask" "F.Paste")
			(net "P1V05_PCH_STBY")
		)
		(pad "AT52" smd circle
			(at 6.86816 2.22885)
			(size 0.381 0.381)
			(layers "F.Cu" "F.Mask" "F.Paste")
			(net "FM_CPU_MSMI_LVT3_N")
		)
		(pad "AT56" smd circle
			(at 8.5852 2.22885)
			(size 0.381 0.381)
			(layers "F.Cu" "F.Mask" "F.Paste")
			(net "XDP_TRST_N")
		)
		(pad "AT59" smd circle
			(at 10.30224 2.22885)
			(size 0.381 0.381)
			(layers "F.Cu" "F.Mask" "F.Paste")
			(net "GND")
		)
		(pad "AT63" smd circle
			(at 12.01928 2.22885)
			(size 0.381 0.381)
			(layers "F.Cu" "F.Mask" "F.Paste")
			(net "SATA6G_PCH_PCIE_UP_SATA_RXP<0>")
		)
		(pad "AT66" smd circle
			(at 13.73632 2.22885)
			(size 0.381 0.381)
			(layers "F.Cu" "F.Mask" "F.Paste")
			(net "Net_137")
		)
		(pad "AT69" smd circle
			(at 15.064994 2.500122)
			(size 0.3048 0.3048)
			(layers "F.Cu" "F.Mask" "F.Paste")
			(net "TP_PCH_RSVD6")
		)
		(pad "AT71" smd circle
			(at 15.895066 2.500122)
			(size 0.3048 0.3048)
			(layers "F.Cu" "F.Mask" "F.Paste")
			(net "TP_PCH_RSVD22")
		)
		(pad "AU9" smd circle
			(at -12.8778 2.72415)
			(size 0.381 0.381)
			(layers "F.Cu" "F.Mask" "F.Paste")
			(net "SMB_LAN_STBY_LVC3_SCL_R2")
		)
		(pad "AU13" smd circle
			(at -11.16076 2.72415)
			(size 0.381 0.381)
			(layers "F.Cu" "F.Mask" "F.Paste")
			(net "FM_IE_DISABLE_N")
		)
		(pad "AU17" smd circle
			(at -9.44372 2.72415)
			(size 0.381 0.381)
			(layers "F.Cu" "F.Mask" "F.Paste")
			(net "SGPIO_PCH_SSATA_LOAD")
		)
		(pad "AU20" smd circle
			(at -7.72668 2.72415)
			(size 0.381 0.381)
			(layers "F.Cu" "F.Mask" "F.Paste")
			(net "SMB_LAN_STBY_LVC3_SDA_R2")
		)
		(pad "AU24" smd circle
			(at -6.00964 2.72415)
			(size 0.381 0.381)
			(layers "F.Cu" "F.Mask" "F.Paste")
			(net "P3V3_STBY")
		)
		(pad "AU26" smd circle
			(at -5.20065 2.95275 180)
			(size 0.381 0.381)
			(layers "F.Cu" "F.Mask" "F.Paste")
			(net "GND")
		)
		(pad "AU27" smd circle
			(at -4.40055 2.95275 180)
			(size 0.381 0.381)
			(layers "F.Cu" "F.Mask" "F.Paste")
			(net "P3V3_STBY")
		)
		(pad "AU29" smd circle
			(at -3.60045 2.95275 180)
			(size 0.381 0.381)
			(layers "F.Cu" "F.Mask" "F.Paste")
			(net "P1V8_PCH_STBY")
		)
		(pad "AU30" smd circle
			(at -2.80035 2.95275 180)
			(size 0.381 0.381)
			(layers "F.Cu" "F.Mask" "F.Paste")
			(net "GND")
		)
		(pad "AU32" smd circle
			(at -2.00025 2.95275 180)
			(size 0.381 0.381)
			(layers "F.Cu" "F.Mask" "F.Paste")
			(net "PVNN_PCH_STBY")
		)
		(pad "AU34" smd circle
			(at -1.20015 2.95275 180)
			(size 0.381 0.381)
			(layers "F.Cu" "F.Mask" "F.Paste")
			(net "PVNN_PCH_STBY")
		)
		(pad "AU36" smd circle
			(at -0.40005 2.95275 180)
			(size 0.381 0.381)
			(layers "F.Cu" "F.Mask" "F.Paste")
			(net "PVNN_PCH_STBY")
		)
		(pad "AU37" smd circle
			(at 0.40005 2.95275 180)
			(size 0.381 0.381)
			(layers "F.Cu" "F.Mask" "F.Paste")
			(net "P1V05_PCH_STBY")
		)
		(pad "AU39" smd circle
			(at 1.20015 2.95275 180)
			(size 0.381 0.381)
			(layers "F.Cu" "F.Mask" "F.Paste")
			(net "P1V05_PCH_STBY")
		)
		(pad "AU41" smd circle
			(at 2.00025 2.95275 180)
			(size 0.381 0.381)
			(layers "F.Cu" "F.Mask" "F.Paste")
			(net "GND")
		)
		(pad "AU43" smd circle
			(at 2.80035 2.95275 180)
			(size 0.381 0.381)
			(layers "F.Cu" "F.Mask" "F.Paste")
			(net "P1V05_PCH_STBY")
		)
		(pad "AU45" smd circle
			(at 3.60045 2.95275 180)
			(size 0.381 0.381)
			(layers "F.Cu" "F.Mask" "F.Paste")
			(net "P1V05_PCH_STBY")
		)
		(pad "AU46" smd circle
			(at 4.40055 2.95275 180)
			(size 0.381 0.381)
			(layers "F.Cu" "F.Mask" "F.Paste")
			(net "GND")
		)
		(pad "AU48" smd circle
			(at 5.20065 2.95275 180)
			(size 0.381 0.381)
			(layers "F.Cu" "F.Mask" "F.Paste")
			(net "P1V05_PCH_STBY_WM26_PLL")
		)
		(pad "AU50" smd circle
			(at 6.00964 2.72415)
			(size 0.381 0.381)
			(layers "F.Cu" "F.Mask" "F.Paste")
			(net "GND")
		)
		(pad "AU54" smd circle
			(at 7.72668 2.72415)
			(size 0.381 0.381)
			(layers "F.Cu" "F.Mask" "F.Paste")
			(net "GND")
		)
		(pad "AU58" smd circle
			(at 9.44372 2.72415)
			(size 0.381 0.381)
			(layers "F.Cu" "F.Mask" "F.Paste")
			(net "IRQ_UV_DETECT_N")
		)
		(pad "AU61" smd circle
			(at 11.16076 2.72415)
			(size 0.381 0.381)
			(layers "F.Cu" "F.Mask" "F.Paste")
			(net "GND")
		)
		(pad "AU65" smd circle
			(at 12.8778 2.72415)
			(size 0.381 0.381)
			(layers "F.Cu" "F.Mask" "F.Paste")
			(net "Net_140")
		)
		(pad "AV1" smd oval
			(at -16.310102 2.999994 180)
			(size 0.254 0.3302)
			(layers "F.Cu" "F.Mask" "F.Paste")
			(net "Net_459")
		)
		(pad "AV3" smd circle
			(at -15.48003 2.999994 180)
			(size 0.3048 0.3048)
			(layers "F.Cu" "F.Mask" "F.Paste")
			(net "Net_464")
		)
		(pad "AV5" smd circle
			(at -14.649958 2.999994 180)
			(size 0.3048 0.3048)
			(layers "F.Cu" "F.Mask" "F.Paste")
			(net "GND")
		)
		(pad "AV7" smd circle
			(at -13.73632 3.21945)
			(size 0.381 0.381)
			(layers "F.Cu" "F.Mask" "F.Paste")
			(net "FM_BOARD_SKU_ID2")
		)
		(pad "AV11" smd circle
			(at -12.01928 3.21945)
			(size 0.381 0.381)
			(layers "F.Cu" "F.Mask" "F.Paste")
			(net "Net_465")
		)
		(pad "AV15" smd circle
			(at -10.30224 3.21945)
			(size 0.381 0.381)
			(layers "F.Cu" "F.Mask" "F.Paste")
			(net "Net_472")
		)
		(pad "AV18" smd circle
			(at -8.5852 3.21945)
			(size 0.381 0.381)
			(layers "F.Cu" "F.Mask" "F.Paste")
			(net "FM_CPU1_THERMTRIP_LATCH_LVT3_N")
		)
		(pad "AV22" smd circle
			(at -6.86816 3.21945)
			(size 0.381 0.381)
			(layers "F.Cu" "F.Mask" "F.Paste")
			(net "GND")
		)
		(pad "AV52" smd circle
			(at 6.86816 3.21945)
			(size 0.381 0.381)
			(layers "F.Cu" "F.Mask" "F.Paste")
			(net "FM_CPU_ERR2_LVT3_N")
		)
		(pad "AV56" smd circle
			(at 8.5852 3.21945)
			(size 0.381 0.381)
			(layers "F.Cu" "F.Mask" "F.Paste")
			(net "LED_PCH_SATA_HDD_N")
		)
		(pad "AV59" smd circle
			(at 10.30224 3.21945)
			(size 0.381 0.381)
			(layers "F.Cu" "F.Mask" "F.Paste")
			(net "GND")
		)
		(pad "AV63" smd circle
			(at 12.01928 3.21945)
			(size 0.381 0.381)
			(layers "F.Cu" "F.Mask" "F.Paste")
			(net "Net_136")
		)
		(pad "AV66" smd circle
			(at 13.73632 3.21945)
			(size 0.381 0.381)
			(layers "F.Cu" "F.Mask" "F.Paste")
			(net "Net_141")
		)
		(pad "AV68" smd circle
			(at 14.649958 2.999994)
			(size 0.3048 0.3048)
			(layers "F.Cu" "F.Mask" "F.Paste")
			(net "GND")
		)
		(pad "AV70" smd circle
			(at 15.48003 2.999994)
			(size 0.3048 0.3048)
			(layers "F.Cu" "F.Mask" "F.Paste")
			(net "P3E_PCH_M2_RX_DP<3>")
		)
		(pad "AV72" smd oval
			(at 16.310102 2.999994 180)
			(size 0.254 0.3302)
			(layers "F.Cu" "F.Mask" "F.Paste")
			(net "P3E_PCH_M2_RX_DN<3>")
		)
		(pad "AW2" smd circle
			(at -15.895066 3.50012 180)
			(size 0.3048 0.3048)
			(layers "F.Cu" "F.Mask" "F.Paste")
			(net "Net_460")
		)
		(pad "AW4" smd circle
			(at -15.064994 3.50012 180)
			(size 0.3048 0.3048)
			(layers "F.Cu" "F.Mask" "F.Paste")
			(net "FM_BACKUP_BIOS_SEL_N")
		)
		(pad "AW9" smd circle
			(at -12.8778 3.71475)
			(size 0.381 0.381)
			(layers "F.Cu" "F.Mask" "F.Paste")
			(net "GND")
		)
		(pad "AW13" smd circle
			(at -11.16076 3.71475)
			(size 0.381 0.381)
			(layers "F.Cu" "F.Mask" "F.Paste")
			(net "GND")
		)
		(pad "AW17" smd circle
			(at -9.44372 3.71475)
			(size 0.381 0.381)
			(layers "F.Cu" "F.Mask" "F.Paste")
			(net "GND")
		)
		(pad "AW20" smd circle
			(at -7.72668 3.71475)
			(size 0.381 0.381)
			(layers "F.Cu" "F.Mask" "F.Paste")
			(net "Net_468")
		)
		(pad "AW24" smd circle
			(at -6.00964 3.71475)
			(size 0.381 0.381)
			(layers "F.Cu" "F.Mask" "F.Paste")
			(net "P3V3_STBY")
		)
		(pad "AW26" smd circle
			(at -5.20065 3.75285 180)
			(size 0.381 0.381)
			(layers "F.Cu" "F.Mask" "F.Paste")
			(net "GND")
		)
		(pad "AW27" smd circle
			(at -4.40055 3.75285 180)
			(size 0.381 0.381)
			(layers "F.Cu" "F.Mask" "F.Paste")
			(net "P1V8_PCH_STBY")
		)
		(pad "AW29" smd circle
			(at -3.60045 3.75285 180)
			(size 0.381 0.381)
			(layers "F.Cu" "F.Mask" "F.Paste")
			(net "P1V8_PCH_STBY")
		)
		(pad "AW30" smd circle
			(at -2.80035 3.75285 180)
			(size 0.381 0.381)
			(layers "F.Cu" "F.Mask" "F.Paste")
			(net "GND")
		)
		(pad "AW32" smd circle
			(at -2.00025 3.75285 180)
			(size 0.381 0.381)
			(layers "F.Cu" "F.Mask" "F.Paste")
			(net "GND")
		)
		(pad "AW34" smd circle
			(at -1.20015 3.75285 180)
			(size 0.381 0.381)
			(layers "F.Cu" "F.Mask" "F.Paste")
			(net "GND")
		)
		(pad "AW36" smd circle
			(at -0.40005 3.75285 180)
			(size 0.381 0.381)
			(layers "F.Cu" "F.Mask" "F.Paste")
			(net "GND")
		)
		(pad "AW37" smd circle
			(at 0.40005 3.75285 180)
			(size 0.381 0.381)
			(layers "F.Cu" "F.Mask" "F.Paste")
			(net "GND")
		)
		(pad "AW39" smd circle
			(at 1.20015 3.75285 180)
			(size 0.381 0.381)
			(layers "F.Cu" "F.Mask" "F.Paste")
			(net "GND")
		)
		(pad "AW41" smd circle
			(at 2.00025 3.75285 180)
			(size 0.381 0.381)
			(layers "F.Cu" "F.Mask" "F.Paste")
			(net "GND")
		)
		(pad "AW43" smd circle
			(at 2.80035 3.75285 180)
			(size 0.381 0.381)
			(layers "F.Cu" "F.Mask" "F.Paste")
			(net "P1V05_PCH_STBY")
		)
		(pad "AW45" smd circle
			(at 3.60045 3.75285 180)
			(size 0.381 0.381)
			(layers "F.Cu" "F.Mask" "F.Paste")
			(net "P1V05_PCH_STBY")
		)
		(pad "AW46" smd circle
			(at 4.40055 3.75285 180)
			(size 0.381 0.381)
			(layers "F.Cu" "F.Mask" "F.Paste")
			(net "GND")
		)
		(pad "AW48" smd circle
			(at 5.20065 3.75285 180)
			(size 0.381 0.381)
			(layers "F.Cu" "F.Mask" "F.Paste")
			(net "P1V05_PCH_STBY_WM26_PLL")
		)
		(pad "AW50" smd circle
			(at 6.00964 3.71475)
			(size 0.381 0.381)
			(layers "F.Cu" "F.Mask" "F.Paste")
			(net "GND")
		)
		(pad "AW54" smd circle
			(at 7.72668 3.71475)
			(size 0.381 0.381)
			(layers "F.Cu" "F.Mask" "F.Paste")
			(net "IRQ_BMC_PCH_SMI_LPC_N")
		)
		(pad "AW58" smd circle
			(at 9.44372 3.71475)
			(size 0.381 0.381)
			(layers "F.Cu" "F.Mask" "F.Paste")
			(net "GND")
		)
		(pad "AW61" smd circle
			(at 11.16076 3.71475)
			(size 0.381 0.381)
			(layers "F.Cu" "F.Mask" "F.Paste")
			(net "GND")
		)
		(pad "AW65" smd circle
			(at 12.8778 3.71475)
			(size 0.381 0.381)
			(layers "F.Cu" "F.Mask" "F.Paste")
			(net "Net_135")
		)
		(pad "AW69" smd circle
			(at 15.064994 3.50012)
			(size 0.3048 0.3048)
			(layers "F.Cu" "F.Mask" "F.Paste")
			(net "P3E_PCH_M2_RX_DP<2>")
		)
		(pad "AW71" smd circle
			(at 15.895066 3.50012)
			(size 0.3048 0.3048)
			(layers "F.Cu" "F.Mask" "F.Paste")
			(net "P3E_PCH_M2_RX_DN<2>")
		)
		(pad "AY1" smd oval
			(at -16.310102 3.999992 180)
			(size 0.254 0.3302)
			(layers "F.Cu" "F.Mask" "F.Paste")
			(net "Net_478")
		)
		(pad "AY3" smd circle
			(at -15.48003 3.999992 180)
			(size 0.3048 0.3048)
			(layers "F.Cu" "F.Mask" "F.Paste")
			(net "Net_461")
		)
		(pad "AY5" smd circle
			(at -14.649958 3.999992 180)
			(size 0.3048 0.3048)
			(layers "F.Cu" "F.Mask" "F.Paste")
			(net "GND")
		)
		(pad "AY7" smd circle
			(at -13.73632 4.21005)
			(size 0.381 0.381)
			(layers "F.Cu" "F.Mask" "F.Paste")
			(net "Net_470")
		)
		(pad "AY11" smd circle
			(at -12.01928 4.21005)
			(size 0.381 0.381)
			(layers "F.Cu" "F.Mask" "F.Paste")
			(net "Net_475")
		)
		(pad "AY15" smd circle
			(at -10.30224 4.21005)
			(size 0.381 0.381)
			(layers "F.Cu" "F.Mask" "F.Paste")
			(net "Net_467")
		)
		(pad "AY18" smd circle
			(at -8.5852 4.21005)
			(size 0.381 0.381)
			(layers "F.Cu" "F.Mask" "F.Paste")
			(net "FM_BOARD_SKU_ID1")
		)
		(pad "AY22" smd circle
			(at -6.86816 4.21005)
			(size 0.381 0.381)
			(layers "F.Cu" "F.Mask" "F.Paste")
			(net "GND")
		)
		(pad "AY52" smd circle
			(at 6.86816 4.21005)
			(size 0.381 0.381)
			(layers "F.Cu" "F.Mask" "F.Paste")
			(net "FM_CPU1_RC_ERROR_R1_N")
		)
		(pad "AY56" smd circle
			(at 8.5852 4.21005)
			(size 0.381 0.381)
			(layers "F.Cu" "F.Mask" "F.Paste")
			(net "GND")
		)
		(pad "AY59" smd circle
			(at 10.30224 4.21005)
			(size 0.381 0.381)
			(layers "F.Cu" "F.Mask" "F.Paste")
			(net "SATA6G_S1_RX_DN")
		)
		(pad "AY63" smd circle
			(at 12.01928 4.21005)
			(size 0.381 0.381)
			(layers "F.Cu" "F.Mask" "F.Paste")
			(net "GND")
		)
		(pad "AY66" smd circle
			(at 13.73632 4.21005)
			(size 0.381 0.381)
			(layers "F.Cu" "F.Mask" "F.Paste")
			(net "Net_139")
		)
		(pad "AY68" smd circle
			(at 14.649958 3.999992)
			(size 0.3048 0.3048)
			(layers "F.Cu" "F.Mask" "F.Paste")
			(net "GND")
		)
		(pad "AY70" smd circle
			(at 15.48003 3.999992)
			(size 0.3048 0.3048)
			(layers "F.Cu" "F.Mask" "F.Paste")
			(net "P3E_PCH_M2_RX_DP<1>")
		)
		(pad "AY72" smd oval
			(at 16.310102 3.999992 180)
			(size 0.254 0.3302)
			(layers "F.Cu" "F.Mask" "F.Paste")
			(net "P3E_PCH_M2_RX_DN<1>")
		)
		(pad "B10" smd circle
			(at -12.500102 -12.895072 90)
			(size 0.3048 0.3048)
			(layers "F.Cu" "F.Mask" "F.Paste")
			(net "TP_PCH_RSVD17")
		)
		(pad "B12" smd circle
			(at -11.500104 -12.895072 90)
			(size 0.3048 0.3048)
			(layers "F.Cu" "F.Mask" "F.Paste")
			(net "GND")
		)
		(pad "B14" smd circle
			(at -10.500106 -12.895072 90)
			(size 0.3048 0.3048)
			(layers "F.Cu" "F.Mask" "F.Paste")
			(net "FM_CPU0_RC_ERROR_R_N")
		)
		(pad "B16" smd circle
			(at -9.500108 -12.895072 90)
			(size 0.3048 0.3048)
			(layers "F.Cu" "F.Mask" "F.Paste")
			(net "FM_SLPS4_N")
		)
		(pad "B19" smd circle
			(at -8.50011 -12.895072 90)
			(size 0.3048 0.3048)
			(layers "F.Cu" "F.Mask" "F.Paste")
			(net "GND")
		)
		(pad "B21" smd circle
			(at -7.500112 -12.895072 90)
			(size 0.3048 0.3048)
			(layers "F.Cu" "F.Mask" "F.Paste")
			(net "CLK_100M_MEZZ4_DN")
		)
	)
)
